(kicad_pcb
	(version 20241229)
	(generator "pcbnew")
	(generator_version "9.0")
	(general
		(thickness 1.552)
		(legacy_teardrops no)
	)
	(paper "A4")
	(title_block
		(date "2023-07-25")
		(rev "1.1.4")
		(comment 9 "footprints 267-270 of 379")
	)
	(layers
		(0 "F.Cu" signal)
		(4 "In1.Cu" signal)
		(6 "In2.Cu" signal)
		(8 "In3.Cu" signal)
		(10 "In4.Cu" signal)
		(12 "In5.Cu" signal)
		(14 "In6.Cu" signal)
		(2 "B.Cu" signal)
		(9 "F.Adhes" user "F.Adhesive")
		(11 "B.Adhes" user "B.Adhesive")
		(13 "F.Paste" user)
		(15 "B.Paste" user)
		(5 "F.SilkS" user "F.Silkscreen")
		(7 "B.SilkS" user "B.Silkscreen")
		(1 "F.Mask" user)
		(3 "B.Mask" user)
		(17 "Dwgs.User" user "User.Drawings")
		(19 "Cmts.User" user "User.Comments")
		(21 "Eco1.User" user "User.Eco1")
		(23 "Eco2.User" user "User.Eco2")
		(25 "Edge.Cuts" user)
		(27 "Margin" user)
		(31 "F.CrtYd" user "F.Courtyard")
		(29 "B.CrtYd" user "B.Courtyard")
		(35 "F.Fab" user)
		(33 "B.Fab" user)
	)
	(footprint "antmicro-footprints:C_0201"
		(layer "B.Cu")
		(at 128.3 87.1 180)
		(descr "Capacitor SMD 0201")
		(tags "capacitor SMD 0201")
		(property "Reference" "C36"
			(at 8.47 12.295736 0)
			(layer "B.SilkS")
			(effects
				(font
					(size 0.65 0.65)
					(thickness 0.15)
				)
				(justify left bottom mirror)
			)
		)
		(property "Value" "C_100n_0201"
			(at 0 -1.4 0)
			(layer "B.Fab")
			(hide yes)
			(effects
				(font
					(size 0.7 0.7)
					(thickness 0.15)
				)
				(justify left bottom mirror)
			)
		)
		(property "Datasheet" "https://www.yageo.com/en/Chart/Download/pdf/CC0201KRX6S5BB104"
			(at 0 0 180)
			(layer "F.Fab")
			(hide yes)
			(effects
				(font
					(size 1.27 1.27)
					(thickness 0.15)
				)
			)
		)
		(property "Description" "SMD Multilayer Ceramic Capacitor, 0.1 µF, 6.3 V, 0201 [0603 Metric], ± 10%, X6S, CC Series"
			(at 0 0 180)
			(layer "F.Fab")
			(hide yes)
			(effects
				(font
					(size 1.27 1.27)
					(thickness 0.15)
				)
			)
		)
		(property "Author" "Antmicro"
			(at 256.6 174.2 0)
			(layer "B.Fab")
			(hide yes)
			(effects
				(font
					(size 1 1)
					(thickness 0.15)
				)
				(justify mirror)
			)
		)
		(property "Dielectric" ""
			(at 256.6 174.2 0)
			(layer "B.Fab")
			(hide yes)
			(effects
				(font
					(size 1 1)
					(thickness 0.15)
				)
				(justify mirror)
			)
		)
		(property "License" "Apache-2.0"
			(at 256.6 174.2 0)
			(layer "B.Fab")
			(hide yes)
			(effects
				(font
					(size 1 1)
					(thickness 0.15)
				)
				(justify mirror)
			)
		)
		(property "MPN" "CC0201KRX6S5BB104"
			(at 256.6 174.2 0)
			(layer "B.Fab")
			(hide yes)
			(effects
				(font
					(size 1 1)
					(thickness 0.15)
				)
				(justify mirror)
			)
		)
		(property "Manufacturer" "YAGEO"
			(at 256.6 174.2 0)
			(layer "B.Fab")
			(hide yes)
			(effects
				(font
					(size 1 1)
					(thickness 0.15)
				)
				(justify mirror)
			)
		)
		(property "Val" "100n"
			(at 256.6 174.2 0)
			(layer "B.Fab")
			(hide yes)
			(effects
				(font
					(size 1 1)
					(thickness 0.15)
				)
				(justify mirror)
			)
		)
		(property "Voltage" ""
			(at 256.6 174.2 0)
			(layer "B.Fab")
			(hide yes)
			(effects
				(font
					(size 1 1)
					(thickness 0.15)
				)
				(justify mirror)
			)
		)
		(property "Public" "False"
			(at 0 0 180)
			(unlocked yes)
			(layer "B.Fab")
			(hide yes)
			(effects
				(font
					(size 1 1)
					(thickness 0.15)
				)
				(justify mirror)
			)
		)
		(sheetname "/DDR3/")
		(sheetfile "ddr3.kicad_sch")
		(attr smd)
		(fp_rect
			(start -0.7 0.35)
			(end 0.7 -0.35)
			(stroke
				(width 0.05)
				(type default)
			)
			(fill no)
			(layer "B.CrtYd")
		)
		(fp_rect
			(start 0.3 -0.15)
			(end -0.301 0.149)
			(stroke
				(width 0.15)
				(type solid)
			)
			(fill no)
			(layer "B.Fab")
		)
		(fp_text user "Author: Antmicro"
			(at -0.72 -5.4 0)
			(layer "B.Fab")
			(effects
				(font
					(size 0.7 0.7)
					(thickness 0.15)
				)
				(justify left bottom mirror)
			)
		)
		(fp_text user "${REFERENCE}"
			(at -0.72 -3.4 0)
			(layer "B.Fab")
			(effects
				(font
					(size 0.7 0.7)
					(thickness 0.15)
				)
				(justify left bottom mirror)
			)
		)
		(fp_text user "License: Apache-2.0"
			(at -0.72 -4.4 0)
			(layer "B.Fab")
			(effects
				(font
					(size 0.7 0.7)
					(thickness 0.15)
				)
				(justify left bottom mirror)
			)
		)
		(pad "" smd roundrect
			(at -0.349 0.002 180)
			(size 0.318 0.36)
			(layers "B.Paste")
			(roundrect_rratio 0.25)
		)
		(pad "" smd roundrect
			(at 0.341 0.002 180)
			(size 0.318 0.36)
			(layers "B.Paste")
			(roundrect_rratio 0.25)
		)
		(pad "1" smd roundrect
			(at -0.321 0.002 180)
			(size 0.46 0.4)
			(layers "B.Cu" "B.Mask")
			(roundrect_rratio 0.25)
			(net 248 "+1V5")
			(pintype "passive")
		)
		(pad "2" smd roundrect
			(at 0.32 0.002 180)
			(size 0.46 0.4)
			(layers "B.Cu" "B.Mask")
			(roundrect_rratio 0.25)
			(net 1 "GND")
			(pintype "passive")
		)
	)
	(footprint "antmicro-footprints:C_0402_1005Metric"
		(layer "B.Cu")
		(at 142.5 85.75 -90)
		(descr "Capacitor SMD 0402")
		(tags "capacitor SMD 0402")
		(property "Reference" "C123"
			(at -1.21 0.7 90)
			(layer "B.SilkS")
			(effects
				(font
					(size 0.65 0.65)
					(thickness 0.15)
				)
				(justify left bottom mirror)
			)
		)
		(property "Value" "C_100n_0402"
			(at 0 -1.4 90)
			(layer "B.Fab")
			(hide yes)
			(effects
				(font
					(size 0.7 0.7)
					(thickness 0.15)
				)
				(justify left bottom mirror)
			)
		)
		(property "Datasheet" "https://www.murata.com/products/productdetail?partno=GRM155R61H104KE14%23"
			(at 0 0 270)
			(layer "F.Fab")
			(hide yes)
			(effects
				(font
					(size 1.27 1.27)
					(thickness 0.15)
				)
			)
		)
		(property "Description" "SMD Multilayer Ceramic Capacitor, 0.1 µF, 50 V, 0402 [1005 Metric], ± 10%, X5R, GRM Series"
			(at 0 0 270)
			(layer "F.Fab")
			(hide yes)
			(effects
				(font
					(size 1.27 1.27)
					(thickness 0.15)
				)
			)
		)
		(property "Author" "Antmicro"
			(at 56.75 228.25 0)
			(layer "B.Fab")
			(hide yes)
			(effects
				(font
					(size 1 1)
					(thickness 0.15)
				)
				(justify mirror)
			)
		)
		(property "Dielectric" "X5R"
			(at 56.75 228.25 0)
			(layer "B.Fab")
			(hide yes)
			(effects
				(font
					(size 1 1)
					(thickness 0.15)
				)
				(justify mirror)
			)
		)
		(property "License" "Apache-2.0"
			(at 56.75 228.25 0)
			(layer "B.Fab")
			(hide yes)
			(effects
				(font
					(size 1 1)
					(thickness 0.15)
				)
				(justify mirror)
			)
		)
		(property "MPN" "GRM155R61H104KE14D"
			(at 56.75 228.25 0)
			(layer "B.Fab")
			(hide yes)
			(effects
				(font
					(size 1 1)
					(thickness 0.15)
				)
				(justify mirror)
			)
		)
		(property "Manufacturer" "Murata"
			(at 56.75 228.25 0)
			(layer "B.Fab")
			(hide yes)
			(effects
				(font
					(size 1 1)
					(thickness 0.15)
				)
				(justify mirror)
			)
		)
		(property "Val" "100n"
			(at 56.75 228.25 0)
			(layer "B.Fab")
			(hide yes)
			(effects
				(font
					(size 1 1)
					(thickness 0.15)
				)
				(justify mirror)
			)
		)
		(property "Voltage" "50V"
			(at 56.75 228.25 0)
			(layer "B.Fab")
			(hide yes)
			(effects
				(font
					(size 1 1)
					(thickness 0.15)
				)
				(justify mirror)
			)
		)
		(sheetname "/Peripherals/")
		(sheetfile "peripherals.kicad_sch")
		(attr smd)
		(fp_rect
			(start -0.925 0.47)
			(end 0.925 -0.47)
			(stroke
				(width 0.05)
				(type default)
			)
			(fill no)
			(layer "B.CrtYd")
		)
		(fp_line
			(start -0.494 0.25)
			(end 0.504 0.25)
			(stroke
				(width 0.15)
				(type solid)
			)
			(layer "B.Fab")
		)
		(fp_line
			(start 0.504 0.25)
			(end 0.504 -0.248)
			(stroke
				(width 0.15)
				(type solid)
			)
			(layer "B.Fab")
		)
		(fp_line
			(start -0.494 -0.248)
			(end -0.494 0.25)
			(stroke
				(width 0.15)
				(type solid)
			)
			(layer "B.Fab")
		)
		(fp_line
			(start 0.504 -0.248)
			(end -0.494 -0.248)
			(stroke
				(width 0.15)
				(type solid)
			)
			(layer "B.Fab")
		)
		(fp_text user "${REFERENCE}"
			(at -0.939 -4.599 90)
			(layer "B.Fab")
			(effects
				(font
					(size 0.7 0.7)
					(thickness 0.15)
				)
				(justify left bottom mirror)
			)
		)
		(fp_text user "License: Apache-2.0"
			(at -0.939 -5.799 90)
			(layer "B.Fab")
			(effects
				(font
					(size 0.7 0.7)
					(thickness 0.15)
				)
				(justify left bottom mirror)
			)
		)
		(fp_text user "Author: Antmicro"
			(at -0.939 -3.399 90)
			(layer "B.Fab")
			(effects
				(font
					(size 0.7 0.7)
					(thickness 0.15)
				)
				(justify left bottom mirror)
			)
		)
		(pad "1" smd roundrect
			(at -0.48 0 270)
			(size 0.59 0.64)
			(layers "B.Cu" "B.Mask" "B.Paste")
			(roundrect_rratio 0.25)
			(net 1 "GND")
			(pintype "passive")
		)
		(pad "2" smd roundrect
			(at 0.48 0 270)
			(size 0.59 0.64)
			(layers "B.Cu" "B.Mask" "B.Paste")
			(roundrect_rratio 0.25)
			(net 348 "/Peripherals/FTDI_VCCIO")
			(pintype "passive")
		)
	)
	(footprint "antmicro-footprints:C_0603_1608Metric"
		(layer "B.Cu")
		(at 161.49 72.1 90)
		(descr "Capacitor SMD 0603")
		(tags "capacitor 0603")
		(property "Reference" "C4"
			(at -0.34 1.54 90)
			(layer "B.SilkS")
			(effects
				(font
					(size 0.65 0.65)
					(thickness 0.15)
				)
				(justify right bottom mirror)
			)
		)
		(property "Value" "C_1u_0603"
			(at 0 -1.6 90)
			(layer "B.Fab")
			(hide yes)
			(effects
				(font
					(size 0.7 0.7)
					(thickness 0.15)
				)
				(justify right bottom mirror)
			)
		)
		(property "Datasheet" "https://spicat.kyocera-avx.com/product/mlcc/chartview/0603YD105KAT2A/"
			(at 0 0 90)
			(layer "F.Fab")
			(hide yes)
			(effects
				(font
					(size 1.27 1.27)
					(thickness 0.15)
				)
			)
		)
		(property "Description" "SMD Multilayer Ceramic Capacitor, 1 µF, 16 V, 0603 [1608 Metric], ± 10%, X5R, AVX 0603 MLCC"
			(at 0 0 90)
			(layer "F.Fab")
			(hide yes)
			(effects
				(font
					(size 1.27 1.27)
					(thickness 0.15)
				)
			)
		)
		(property "Author" "Antmicro"
			(at 233.59 -89.39 0)
			(layer "B.Fab")
			(hide yes)
			(effects
				(font
					(size 1 1)
					(thickness 0.15)
				)
				(justify mirror)
			)
		)
		(property "Dielectric" ""
			(at 233.59 -89.39 0)
			(layer "B.Fab")
			(hide yes)
			(effects
				(font
					(size 1 1)
					(thickness 0.15)
				)
				(justify mirror)
			)
		)
		(property "License" "Apache-2.0"
			(at 233.59 -89.39 0)
			(layer "B.Fab")
			(hide yes)
			(effects
				(font
					(size 1 1)
					(thickness 0.15)
				)
				(justify mirror)
			)
		)
		(property "MPN" "0603YD105KAT2A"
			(at 233.59 -89.39 0)
			(layer "B.Fab")
			(hide yes)
			(effects
				(font
					(size 1 1)
					(thickness 0.15)
				)
				(justify mirror)
			)
		)
		(property "Manufacturer" "KYOCERA AVX"
			(at 233.59 -89.39 0)
			(layer "B.Fab")
			(hide yes)
			(effects
				(font
					(size 1 1)
					(thickness 0.15)
				)
				(justify mirror)
			)
		)
		(property "Val" "1u"
			(at 233.59 -89.39 0)
			(layer "B.Fab")
			(hide yes)
			(effects
				(font
					(size 1 1)
					(thickness 0.15)
				)
				(justify mirror)
			)
		)
		(property "Voltage" ""
			(at 233.59 -89.39 0)
			(layer "B.Fab")
			(hide yes)
			(effects
				(font
					(size 1 1)
					(thickness 0.15)
				)
				(justify mirror)
			)
		)
		(sheetname "/Power Supply/")
		(sheetfile "supply.kicad_sch")
		(attr smd)
		(fp_line
			(start -0.15 -0.4)
			(end 0.15 -0.4)
			(stroke
				(width 0.15)
				(type solid)
			)
			(layer "B.SilkS")
		)
		(fp_line
			(start -0.15 0.4)
			(end 0.15 0.4)
			(stroke
				(width 0.15)
				(type solid)
			)
			(layer "B.SilkS")
		)
		(fp_rect
			(start -1.25 0.65)
			(end 1.25 -0.65)
			(stroke
				(width 0.05)
				(type solid)
			)
			(fill no)
			(layer "B.CrtYd")
		)
		(fp_rect
			(start -0.8 0.4)
			(end 0.8 -0.4)
			(stroke
				(width 0.15)
				(type solid)
			)
			(fill no)
			(layer "B.Fab")
		)
		(fp_text user "License: Apache-2.0"
			(at -1.682 -5.895 270)
			(layer "B.Fab")
			(effects
				(font
					(size 0.7 0.7)
					(thickness 0.15)
				)
				(justify left bottom mirror)
			)
		)
		(fp_text user "Author: Antmicro"
			(at -1.682 -4.894 270)
			(layer "B.Fab")
			(effects
				(font
					(size 0.7 0.7)
					(thickness 0.15)
				)
				(justify left bottom mirror)
			)
		)
		(fp_text user "${REFERENCE}"
			(at -1.682 -3.895 270)
			(layer "B.Fab")
			(effects
				(font
					(size 0.7 0.7)
					(thickness 0.15)
				)
				(justify left bottom mirror)
			)
		)
		(pad "1" smd roundrect
			(at -0.7 0 90)
			(size 0.8 1)
			(layers "B.Cu" "B.Mask" "B.Paste")
			(roundrect_rratio 0.2)
			(net 1 "GND")
			(pintype "passive")
		)
		(pad "2" smd roundrect
			(at 0.7 0 90)
			(size 0.8 1)
			(layers "B.Cu" "B.Mask" "B.Paste")
			(roundrect_rratio 0.2)
			(net 329 "/Power Supply/FFC2_5V_1")
			(pintype "passive")
		)
	)
	(footprint "antmicro-footprints:R_0402_1005Metric"
		(layer "B.Cu")
		(at 152.23 66.25 -90)
		(descr "Resistor SMD 0402")
		(tags "resistor SMD 0402")
		(property "Reference" "R99"
			(at -1.11 0.7 90)
			(layer "B.SilkS")
			(effects
				(font
					(size 0.65 0.65)
					(thickness 0.15)
				)
				(justify left bottom mirror)
			)
		)
		(property "Value" "R_10k_0402"
			(at 0 -1.4 90)
			(layer "B.Fab")
			(hide yes)
			(effects
				(font
					(size 0.7 0.7)
					(thickness 0.15)
				)
				(justify left bottom mirror)
			)
		)
		(property "Datasheet" "https://www.bourns.com/docs/product-datasheets/cr.pdf"
			(at 0 0 270)
			(layer "F.Fab")
			(hide yes)
			(effects
				(font
					(size 1.27 1.27)
					(thickness 0.15)
				)
			)
		)
		(property "Description" "SMD Chip Resistor, 10 kohm, ± 1%, 62.5 mW, 0402 [1005 Metric], Thick Film, General Purpose"
			(at 0 0 270)
			(layer "F.Fab")
			(hide yes)
			(effects
				(font
					(size 1.27 1.27)
					(thickness 0.15)
				)
			)
		)
		(property "Author" "Antmicro"
			(at 85.98 218.48 0)
			(layer "B.Fab")
			(hide yes)
			(effects
				(font
					(size 1 1)
					(thickness 0.15)
				)
				(justify mirror)
			)
		)
		(property "License" "Apache-2.0"
			(at 85.98 218.48 0)
			(layer "B.Fab")
			(hide yes)
			(effects
				(font
					(size 1 1)
					(thickness 0.15)
				)
				(justify mirror)
			)
		)
		(property "MPN" "CR0402-FX-1002GLF"
			(at 85.98 218.48 0)
			(layer "B.Fab")
			(hide yes)
			(effects
				(font
					(size 1 1)
					(thickness 0.15)
				)
				(justify mirror)
			)
		)
		(property "Manufacturer" "Bourns"
			(at 85.98 218.48 0)
			(layer "B.Fab")
			(hide yes)
			(effects
				(font
					(size 1 1)
					(thickness 0.15)
				)
				(justify mirror)
			)
		)
		(property "Tolerance" "1%"
			(at 85.98 218.48 0)
			(layer "B.Fab")
			(hide yes)
			(effects
				(font
					(size 1 1)
					(thickness 0.15)
				)
				(justify mirror)
			)
		)
		(property "Val" "10k"
			(at 85.98 218.48 0)
			(layer "B.Fab")
			(hide yes)
			(effects
				(font
					(size 1 1)
					(thickness 0.15)
				)
				(justify mirror)
			)
		)
		(sheetname "/Power Supply/")
		(sheetfile "supply.kicad_sch")
		(attr smd)
		(fp_rect
			(start -0.925 0.47)
			(end 0.925 -0.47)
			(stroke
				(width 0.05)
				(type default)
			)
			(fill no)
			(layer "B.CrtYd")
		)
		(fp_rect
			(start -0.5 0.25)
			(end 0.5 -0.25)
			(stroke
				(width 0.15)
				(type solid)
			)
			(fill no)
			(layer "B.Fab")
		)
		(fp_text user "${REFERENCE}"
			(at -0.95 -3.168 90)
			(layer "B.Fab")
			(effects
				(font
					(size 0.7 0.7)
					(thickness 0.15)
				)
				(justify left bottom mirror)
			)
		)
		(fp_text user "License: Apache-2.0"
			(at -0.95 -5.169 90)
			(layer "B.Fab")
			(effects
				(font
					(size 0.7 0.7)
					(thickness 0.15)
				)
				(justify left bottom mirror)
			)
		)
		(fp_text user "Author: Antmicro"
			(at -0.95 -4.169 90)
			(layer "B.Fab")
			(effects
				(font
					(size 0.7 0.7)
					(thickness 0.15)
				)
				(justify left bottom mirror)
			)
		)
		(pad "1" smd roundrect
			(at -0.48 0 270)
			(size 0.59 0.64)
			(layers "B.Cu" "B.Mask" "B.Paste")
			(roundrect_rratio 0.25)
			(net 1 "GND")
			(pintype "passive")
		)
		(pad "2" smd roundrect
			(at 0.48 0 270)
			(size 0.59 0.64)
			(layers "B.Cu" "B.Mask" "B.Paste")
			(roundrect_rratio 0.25)
			(net 260 "Net-(Q3-G)")
			(pintype "passive")
		)
	)
)
